(kicad_pcb
	(version 20260206)
	(generator "pcbnew")
	(generator_version "10.0")
	(general
		(thickness 1.6)
		(legacy_teardrops no)
	)
	(paper "A4")
	(title_block
		(title "v1-chassis-manager — T6M_CM_d_v01_1031_1645.brd")
		(comment 1 "Open CloudServer (Microsoft) / footprints 703-707 of 2512")
	)
	(layers
		(0 "F.Cu" signal "TOP")
		(4 "In1.Cu" signal "GND1")
		(6 "In2.Cu" signal "IN1")
		(8 "In3.Cu" signal "VCC1")
		(10 "In4.Cu" signal "VCC2")
		(12 "In5.Cu" signal "GND2")
		(14 "In6.Cu" signal "IN2")
		(16 "In7.Cu" signal "IN3")
		(18 "In8.Cu" signal "GND3")
		(2 "B.Cu" signal "BOTTOM")
		(9 "F.Adhes" user "F.Adhesive")
		(11 "B.Adhes" user "B.Adhesive")
		(13 "F.Paste" user "Package Geometry/Pastemask Top")
		(15 "B.Paste" user "Package Geometry/Pastemask Bottom")
		(5 "F.SilkS" user "Ref Des/Silkscreen Top")
		(7 "B.SilkS" user "Ref Des/Silkscreen Bottom")
		(1 "F.Mask" user "Board Geometry/Soldermask Top")
		(3 "B.Mask" user "Board Geometry/Soldermask Bottom")
		(17 "Dwgs.User" user "User.Drawings")
		(19 "Cmts.User" user "User.Comments")
		(21 "Eco1.User" user "User.Eco1")
		(23 "Eco2.User" user "User.Eco2")
		(25 "Edge.Cuts" user "Board Geometry/Outline")
		(27 "Margin" user)
		(31 "F.CrtYd" user "Package Geometry/Place Bound Top")
		(29 "B.CrtYd" user "Package Geometry/Place Bound Bottom")
		(35 "F.Fab" user "Ref Des/Assembly Top")
		(33 "B.Fab" user "Ref Des/Assembly Bottom")
	)
	(footprint ""
		(layer "F.Cu")
		(at 36.195 -117.943122 -90)
		(property "Reference" "Q40"
			(at -2.407666 0.58674 0)
			(unlocked yes)
			(layer "F.SilkS")
			(effects
				(font
					(size 0.7874 0.5842)
					(thickness 0.1524)
				)
			)
		)
		(property "Value" ""
			(at 0 0 270)
			(layer "F.Fab")
			(effects
				(font
					(size 1.27 1.27)
				)
			)
		)
		(duplicate_pad_numbers_are_jumpers no)
		(fp_line
			(start -1.603248 1.500124)
			(end -1.603248 -1.500124)
			(stroke
				(width 0.1524)
				(type default)
			)
			(layer "F.SilkS")
		)
		(fp_line
			(start 1.603248 1.500124)
			(end -1.603248 1.500124)
			(stroke
				(width 0.1524)
				(type default)
			)
			(layer "F.SilkS")
		)
		(fp_line
			(start -1.603248 -1.500124)
			(end 1.603248 -1.500124)
			(stroke
				(width 0.1524)
				(type default)
			)
			(layer "F.SilkS")
		)
		(fp_line
			(start 1.603248 -1.500124)
			(end 1.603248 1.500124)
			(stroke
				(width 0.1524)
				(type default)
			)
			(layer "F.SilkS")
		)
		(fp_poly
			(pts
				(xy -0.700024 -1.500124) (xy -0.700024 -1.40716) (xy -1.507998 -1.40716) (xy -1.507998 -0.49276)
				(xy -0.700024 -0.49276) (xy -0.700024 0.47244) (xy -1.507998 0.47244) (xy -1.507998 1.41224) (xy -0.700024 1.41224)
				(xy -0.700024 1.500124) (xy 0.700024 1.500124) (xy 0.700024 0.47244) (xy 1.514602 0.47244) (xy 1.514602 -0.46736)
				(xy 0.700024 -0.46736) (xy 0.700024 -1.500124)
			)
			(stroke
				(width 0)
				(type default)
			)
			(fill no)
			(layer "F.CrtYd")
		)
		(fp_line
			(start -0.700024 1.500124)
			(end -0.700024 -1.500124)
			(stroke
				(width 0.1)
				(type default)
			)
			(layer "F.Fab")
		)
		(fp_line
			(start 0.700024 1.500124)
			(end -0.700024 1.500124)
			(stroke
				(width 0.1)
				(type default)
			)
			(layer "F.Fab")
		)
		(fp_line
			(start -0.700024 -1.500124)
			(end 0.700024 -1.500124)
			(stroke
				(width 0.1)
				(type default)
			)
			(layer "F.Fab")
		)
		(fp_line
			(start 0.700024 -1.500124)
			(end 0.700024 1.500124)
			(stroke
				(width 0.1)
				(type default)
			)
			(layer "F.Fab")
		)
		(fp_text user "D"
			(at 1.039114 1.901698 0)
			(unlocked yes)
			(layer "F.SilkS")
			(effects
				(font
					(size 0.635 0.4064)
					(thickness 0.1524)
				)
			)
		)
		(fp_text user "S"
			(at -0.344932 1.689608 0)
			(unlocked yes)
			(layer "F.SilkS")
			(effects
				(font
					(size 0.635 0.4064)
					(thickness 0.1524)
				)
			)
		)
		(fp_text user "G"
			(at -1.79832 -1.857248 0)
			(unlocked yes)
			(layer "F.SilkS")
			(effects
				(font
					(size 0.635 0.4064)
					(thickness 0.1524)
				)
			)
		)
		(fp_text user "S"
			(at -1.025906 2.0066 180)
			(unlocked yes)
			(layer "F.Fab")
			(effects
				(font
					(size 0.7874 0.5842)
					(thickness 0.000001)
				)
			)
		)
		(fp_text user "D"
			(at 2.098294 0.1016 180)
			(unlocked yes)
			(layer "F.Fab")
			(effects
				(font
					(size 0.7874 0.5842)
					(thickness 0.000001)
				)
			)
		)
		(fp_text user "G"
			(at -1.051306 -2.032 180)
			(unlocked yes)
			(layer "F.Fab")
			(effects
				(font
					(size 0.7874 0.5842)
					(thickness 0.000001)
				)
			)
		)
		(pad "D" smd rect
			(at 0.999998 0 180)
			(size 0.8128 0.9144)
			(layers "F.Cu" "F.Mask" "F.Paste")
			(net "FM_CPLD_NODE1_P1V5_EN_LV")
		)
		(pad "G" smd rect
			(at -0.999998 -0.94996 180)
			(size 0.8128 0.9144)
			(layers "F.Cu" "F.Mask" "F.Paste")
			(net "FM_CPLD_NODE1_P1V5_EN_G")
		)
		(pad "S" smd rect
			(at -0.999998 0.94996 180)
			(size 0.8128 0.9144)
			(layers "F.Cu" "F.Mask" "F.Paste")
			(net "FM_CPLD_NODE1_P1V5_EN")
		)
	)
	(footprint ""
		(layer "F.Cu")
		(at 163.252404 -119.684546 180)
		(property "Reference" "Q26"
			(at 4.910074 2.14376 0)
			(unlocked yes)
			(layer "F.SilkS")
			(effects
				(font
					(size 0.7874 0.5842)
					(thickness 0.1524)
				)
				(justify left)
			)
		)
		(property "Value" ""
			(at 0 0 180)
			(layer "F.Fab")
			(effects
				(font
					(size 1.27 1.27)
				)
			)
		)
		(duplicate_pad_numbers_are_jumpers no)
		(fp_line
			(start 2.584196 2.48412)
			(end -0.5842 2.48412)
			(stroke
				(width 0.1524)
				(type default)
			)
			(layer "F.SilkS")
		)
		(fp_line
			(start 2.584196 -0.5842)
			(end 2.584196 2.48412)
			(stroke
				(width 0.1524)
				(type default)
			)
			(layer "F.SilkS")
		)
		(fp_line
			(start -0.5842 2.48412)
			(end -0.5842 -0.5842)
			(stroke
				(width 0.1524)
				(type default)
			)
			(layer "F.SilkS")
		)
		(fp_line
			(start -0.5842 -0.5842)
			(end 2.584196 -0.5842)
			(stroke
				(width 0.1524)
				(type default)
			)
			(layer "F.SilkS")
		)
		(fp_poly
			(pts
				(xy -0.508 -0.4572) (xy 0.299974 -0.4572) (xy 0.299974 -0.54991) (xy 1.700022 -0.54991) (xy 1.700022 0.49276)
				(xy 2.507996 0.49276) (xy 2.507996 1.40716) (xy 1.700022 1.40716) (xy 1.700022 2.450084) (xy 0.299974 2.450084)
				(xy 0.299974 2.35712) (xy -0.508 2.35712)
			)
			(stroke
				(width 0)
				(type default)
			)
			(fill no)
			(layer "F.CrtYd")
		)
		(fp_line
			(start 1.700022 2.450084)
			(end 0.299974 2.450084)
			(stroke
				(width 0.1)
				(type default)
			)
			(layer "F.Fab")
		)
		(fp_line
			(start 1.700022 -0.54991)
			(end 1.700022 2.450084)
			(stroke
				(width 0.1)
				(type default)
			)
			(layer "F.Fab")
		)
		(fp_line
			(start 0.299974 2.450084)
			(end 0.299974 -0.54991)
			(stroke
				(width 0.1)
				(type default)
			)
			(layer "F.Fab")
		)
		(fp_line
			(start 0.299974 -0.54991)
			(end 1.700022 -0.54991)
			(stroke
				(width 0.1)
				(type default)
			)
			(layer "F.Fab")
		)
		(fp_text user "C"
			(at 3.228086 1.035558 0)
			(unlocked yes)
			(layer "F.SilkS")
			(effects
				(font
					(size 0.635 0.4064)
					(thickness 0.1524)
				)
				(justify left)
			)
		)
		(fp_text user "B"
			(at -0.752094 -0.042164 0)
			(unlocked yes)
			(layer "F.SilkS")
			(effects
				(font
					(size 0.635 0.4064)
					(thickness 0.1524)
				)
				(justify left)
			)
		)
		(fp_text user "E"
			(at -1.111504 1.892554 0)
			(unlocked yes)
			(layer "F.SilkS")
			(effects
				(font
					(size 0.635 0.4064)
					(thickness 0.1524)
				)
				(justify left)
			)
		)
		(fp_text user "C"
			(at 2.8702 0.99187 180)
			(unlocked yes)
			(layer "F.Fab")
			(effects
				(font
					(size 0.7874 0.5842)
					(thickness 0.000001)
				)
				(justify left)
			)
		)
		(fp_text user "B"
			(at -1.5494 0.00127 180)
			(unlocked yes)
			(layer "F.Fab")
			(effects
				(font
					(size 0.7874 0.5842)
					(thickness 0.000001)
				)
				(justify left)
			)
		)
		(fp_text user "E"
			(at -1.5748 1.95707 180)
			(unlocked yes)
			(layer "F.Fab")
			(effects
				(font
					(size 0.7874 0.5842)
					(thickness 0.000001)
				)
				(justify left)
			)
		)
		(pad "B" smd rect
			(at 0 0 270)
			(size 0.8128 0.9144)
			(layers "F.Cu" "F.Mask" "F.Paste")
			(net "FM_NODE1_DDR3_SYSPWRGD_R_L")
		)
		(pad "C" smd rect
			(at 1.999996 0.94996 270)
			(size 0.8128 0.9144)
			(layers "F.Cu" "F.Mask" "F.Paste")
			(net "PWRGD_NODE1_DDR3_SYSPWRGD")
		)
		(pad "E" smd rect
			(at 0 1.89992 270)
			(size 0.8128 0.9144)
			(layers "F.Cu" "F.Mask" "F.Paste")
			(net "GND")
		)
	)
	(footprint ""
		(layer "F.Cu")
		(at 17.801336 -59.41568 90)
		(property "Reference" "U50"
			(at 1.163574 3.801872 0)
			(unlocked yes)
			(layer "F.SilkS")
			(effects
				(font
					(size 0.7874 0.5842)
					(thickness 0.1524)
				)
			)
		)
		(property "Value" ""
			(at 0 0 90)
			(layer "F.Fab")
			(effects
				(font
					(size 1.27 1.27)
				)
			)
		)
		(duplicate_pad_numbers_are_jumpers no)
		(fp_line
			(start 1.651 -1.905)
			(end 1.651 1.905)
			(stroke
				(width 0.1524)
				(type default)
			)
			(layer "F.SilkS")
		)
		(fp_line
			(start -1.651 -1.905)
			(end 1.651 -1.905)
			(stroke
				(width 0.1524)
				(type default)
			)
			(layer "F.SilkS")
		)
		(fp_line
			(start 1.651 1.905)
			(end -1.651 1.905)
			(stroke
				(width 0.1524)
				(type default)
			)
			(layer "F.SilkS")
		)
		(fp_line
			(start -1.651 1.905)
			(end -1.651 -1.905)
			(stroke
				(width 0.1524)
				(type default)
			)
			(layer "F.SilkS")
		)
		(fp_poly
			(pts
				(xy -1.524 0.7112) (xy -1.524 1.7526) (xy -0.508 1.7526) (xy -0.508 0.6985) (xy 0.508 0.6985) (xy 0.508 1.7526)
				(xy 1.524 1.7526) (xy 1.524 0.6985) (xy 1.524 -0.6985) (xy 0.508 -0.6985) (xy 0.508 -1.7526) (xy -0.508 -1.7526)
				(xy -0.508 -0.6985) (xy -1.524 -0.6985) (xy -1.524 0.6985)
			)
			(stroke
				(width 0)
				(type default)
			)
			(fill no)
			(layer "F.CrtYd")
		)
		(fp_text user "3"
			(at 1.13919 -1.13538 0)
			(unlocked yes)
			(layer "F.SilkS")
			(effects
				(font
					(size 0.635 0.4064)
					(thickness 0.1524)
				)
			)
		)
		(fp_text user "2"
			(at 1.058164 2.152396 0)
			(unlocked yes)
			(layer "F.SilkS")
			(effects
				(font
					(size 0.635 0.4064)
					(thickness 0.1524)
				)
			)
		)
		(fp_text user "1"
			(at -0.301752 2.556764 0)
			(unlocked yes)
			(layer "F.SilkS")
			(effects
				(font
					(size 0.635 0.4064)
					(thickness 0.1524)
				)
			)
		)
		(pad "1" smd rect
			(at -1.016 1.1176 90)
			(size 1.016 1.27)
			(layers "F.Cu" "F.Mask" "F.Paste")
			(net "GND")
		)
		(pad "2" smd rect
			(at 1.016 1.1176 90)
			(size 1.016 1.27)
			(layers "F.Cu" "F.Mask" "F.Paste")
			(net "P5V_CRT")
		)
		(pad "3" smd rect
			(at 0 -1.1176 90)
			(size 1.016 1.27)
			(layers "F.Cu" "F.Mask" "F.Paste")
			(net "CRT_VSYNC")
		)
	)
	(footprint ""
		(layer "F.Cu")
		(at 11.12012 -4.721352 180)
		(property "Reference" "R472"
			(at 1.137412 -2.351024 0)
			(unlocked yes)
			(layer "F.SilkS")
			(effects
				(font
					(size 0.7874 0.5842)
					(thickness 0.1524)
				)
				(justify left)
			)
		)
		(property "Value" ""
			(at 0 0 180)
			(layer "F.Fab")
			(effects
				(font
					(size 1.27 1.27)
				)
			)
		)
		(duplicate_pad_numbers_are_jumpers no)
		(fp_line
			(start 0.7874 0.4064)
			(end -0.7874 0.4064)
			(stroke
				(width 0.1524)
				(type default)
			)
			(layer "F.SilkS")
		)
		(fp_line
			(start 0.7874 -0.4064)
			(end 0.7874 0.4064)
			(stroke
				(width 0.1524)
				(type default)
			)
			(layer "F.SilkS")
		)
		(fp_line
			(start -0.7874 0.4064)
			(end -0.7874 -0.4064)
			(stroke
				(width 0.1524)
				(type default)
			)
			(layer "F.SilkS")
		)
		(fp_line
			(start -0.7874 -0.4064)
			(end 0.7874 -0.4064)
			(stroke
				(width 0.1524)
				(type default)
			)
			(layer "F.SilkS")
		)
		(fp_poly
			(pts
				(xy -0.508 0.2794) (xy -0.508 0.2286) (xy -0.635 0.2286) (xy -0.635 -0.254) (xy -0.5334 -0.254)
				(xy -0.5334 -0.2794) (xy 0.5334 -0.2794) (xy 0.5334 -0.254) (xy 0.635 -0.254) (xy 0.635 0.254) (xy 0.5334 0.254)
				(xy 0.5334 0.2794)
			)
			(stroke
				(width 0)
				(type default)
			)
			(fill no)
			(layer "F.CrtYd")
		)
		(pad "1" smd rect
			(at 0.40005 0 180)
			(size 0.4572 0.508)
			(layers "F.Cu" "F.Mask" "F.Paste")
			(net "SMB_MUX_CPU_ICS_NODE1_DAT")
		)
		(pad "2" smd rect
			(at -0.40005 0 180)
			(size 0.4572 0.508)
			(layers "F.Cu" "F.Mask" "F.Paste")
			(net "SMB_DIMM_NODE1_DAT")
		)
	)
	(footprint ""
		(layer "F.Cu")
		(at 120.61444 -148.67509 -90)
		(property "Reference" "Q46"
			(at 2.976118 -0.862076 90)
			(unlocked yes)
			(layer "F.SilkS")
			(effects
				(font
					(size 0.7874 0.5842)
					(thickness 0.1524)
				)
			)
		)
		(property "Value" ""
			(at 0 0 270)
			(layer "F.Fab")
			(effects
				(font
					(size 1.27 1.27)
				)
			)
		)
		(duplicate_pad_numbers_are_jumpers no)
		(fp_line
			(start -1.488186 1.500124)
			(end -1.488186 -1.500124)
			(stroke
				(width 0.1524)
				(type default)
			)
			(layer "F.SilkS")
		)
		(fp_line
			(start 1.488186 1.500124)
			(end -1.488186 1.500124)
			(stroke
				(width 0.1524)
				(type default)
			)
			(layer "F.SilkS")
		)
		(fp_line
			(start -1.488186 -1.500124)
			(end 1.488186 -1.500124)
			(stroke
				(width 0.1524)
				(type default)
			)
			(layer "F.SilkS")
		)
		(fp_line
			(start 1.488186 -1.500124)
			(end 1.488186 1.500124)
			(stroke
				(width 0.1524)
				(type default)
			)
			(layer "F.SilkS")
		)
		(fp_poly
			(pts
				(xy -0.700024 1.500124) (xy 0.700024 1.500124) (xy 0.700024 0.3556) (xy 1.4224 0.3556) (xy 1.4224 -0.3556)
				(xy 0.700024 -0.3556) (xy 0.700024 -1.500124) (xy -0.700024 -1.500124) (xy -0.700024 -1.3208) (xy -1.4224 -1.3208)
				(xy -1.4224 -0.5842) (xy -0.700024 -0.5842) (xy -0.700024 0.5842) (xy -1.4224 0.5842) (xy -1.4224 1.3208)
				(xy -0.700024 1.3208)
			)
			(stroke
				(width 0)
				(type default)
			)
			(fill no)
			(layer "F.CrtYd")
		)
		(fp_line
			(start -0.700024 1.500124)
			(end -0.700024 -1.500124)
			(stroke
				(width 0.1)
				(type default)
			)
			(layer "F.Fab")
		)
		(fp_line
			(start 0.700024 1.500124)
			(end -0.700024 1.500124)
			(stroke
				(width 0.1)
				(type default)
			)
			(layer "F.Fab")
		)
		(fp_line
			(start -0.700024 -1.500124)
			(end 0.700024 -1.500124)
			(stroke
				(width 0.1)
				(type default)
			)
			(layer "F.Fab")
		)
		(fp_line
			(start 0.700024 -1.500124)
			(end 0.700024 1.500124)
			(stroke
				(width 0.1)
				(type default)
			)
			(layer "F.Fab")
		)
		(fp_text user "2"
			(at -1.352042 1.6129 0)
			(unlocked yes)
			(layer "F.SilkS")
			(effects
				(font
					(size 0.635 0.4064)
					(thickness 0.1524)
				)
			)
		)
		(fp_text user "1"
			(at -0.298958 -1.702308 0)
			(unlocked yes)
			(layer "F.SilkS")
			(effects
				(font
					(size 0.635 0.4064)
					(thickness 0.1524)
				)
			)
		)
		(fp_text user "3"
			(at 1.230884 -1.908556 0)
			(unlocked yes)
			(layer "F.SilkS")
			(effects
				(font
					(size 0.635 0.4064)
					(thickness 0.1524)
				)
			)
		)
		(fp_text user "2"
			(at -0.90805 1.8542 180)
			(unlocked yes)
			(layer "F.Fab")
			(effects
				(font
					(size 0.7874 0.5842)
					(thickness 0.000001)
				)
			)
		)
		(fp_text user "3"
			(at 2.15773 0 180)
			(unlocked yes)
			(layer "F.Fab")
			(effects
				(font
					(size 0.7874 0.5842)
					(thickness 0.000001)
				)
			)
		)
		(fp_text user "1"
			(at -0.90805 -1.8034 180)
			(unlocked yes)
			(layer "F.Fab")
			(effects
				(font
					(size 0.7874 0.5842)
					(thickness 0.000001)
				)
			)
		)
		(pad "1" smd rect
			(at -0.999998 -0.94996 180)
			(size 0.6096 0.7112)
			(layers "F.Cu" "F.Mask" "F.Paste")
			(net "N52998345")
		)
		(pad "2" smd rect
			(at -0.999998 0.94996 180)
			(size 0.6096 0.7112)
			(layers "F.Cu" "F.Mask" "F.Paste")
			(net "N52998325")
		)
		(pad "3" smd rect
			(at 0.999998 0 180)
			(size 0.6096 0.7112)
			(layers "F.Cu" "F.Mask" "F.Paste")
			(net "POWER_SW3_PWR_CTR_12V")
		)
	)
)
